(kicad_pcb
	(version 20260206)
	(generator "pcbnew")
	(generator_version "10.0")
	(general
		(thickness 1.6)
		(legacy_teardrops no)
	)
	(paper "A4")
	(title_block
		(title "04192023_DAF0TMB3IC0_F0TG_MB_C_brd_V02_OCP.brd")
		(comment 1 "Grand Teton / footprints 78-84 of 8354")
	)
	(layers
		(0 "F.Cu" signal "TOP")
		(4 "In1.Cu" signal "GND")
		(6 "In2.Cu" signal "IN1")
		(8 "In3.Cu" signal "GND1")
		(10 "In4.Cu" signal "IN2")
		(12 "In5.Cu" signal "GND2")
		(14 "In6.Cu" signal "IN3")
		(16 "In7.Cu" signal "GND3")
		(18 "In8.Cu" signal "VCC")
		(20 "In9.Cu" signal "VCC1")
		(22 "In10.Cu" signal "GND4")
		(24 "In11.Cu" signal "IN4")
		(26 "In12.Cu" signal "GND5")
		(28 "In13.Cu" signal "IN5")
		(30 "In14.Cu" signal "GND6")
		(32 "In15.Cu" signal "IN6")
		(34 "In16.Cu" signal "GND7")
		(2 "B.Cu" signal "BOTTOM")
		(9 "F.Adhes" user "F.Adhesive")
		(11 "B.Adhes" user "B.Adhesive")
		(13 "F.Paste" user "Package Geometry/Pastemask Top")
		(15 "B.Paste" user "Package Geometry/Pastemask Bottom")
		(5 "F.SilkS" user "Ref Des/Silkscreen Top")
		(7 "B.SilkS" user "Ref Des/Silkscreen Bottom")
		(1 "F.Mask" user "Board Geometry/Soldermask Top")
		(3 "B.Mask" user "Board Geometry/Soldermask Bottom")
		(17 "Dwgs.User" user "User.Drawings")
		(19 "Cmts.User" user "User.Comments")
		(21 "Eco1.User" user "User.Eco1")
		(23 "Eco2.User" user "User.Eco2")
		(25 "Edge.Cuts" user "Board Geometry/Outline")
		(27 "Margin" user)
		(31 "F.CrtYd" user "Package Geometry/Place Bound Top")
		(29 "B.CrtYd" user "Package Geometry/Place Bound Bottom")
		(35 "F.Fab" user "Ref Des/Assembly Top")
		(33 "B.Fab" user "Ref Des/Assembly Bottom")
	)
	(footprint ""
		(layer "F.Cu")
		(at 159.893 -108.458 180)
		(property "Reference" "R9026"
			(at 0 0 180)
			(layer "F.SilkS")
			(hide yes)
			(effects
				(font
					(size 1.27 1.27)
				)
			)
		)
		(property "Value" ""
			(at 0 0 180)
			(layer "F.Fab")
			(effects
				(font
					(size 1.27 1.27)
				)
			)
		)
		(duplicate_pad_numbers_are_jumpers no)
		(fp_line
			(start 0.7874 0.4064)
			(end -0.7874 0.4064)
			(stroke
				(width 0.1524)
				(type default)
			)
			(layer "F.SilkS")
		)
		(fp_line
			(start 0.7874 -0.4064)
			(end 0.7874 0.4064)
			(stroke
				(width 0.1524)
				(type default)
			)
			(layer "F.SilkS")
		)
		(fp_line
			(start -0.7874 0.4064)
			(end -0.7874 -0.4064)
			(stroke
				(width 0.1524)
				(type default)
			)
			(layer "F.SilkS")
		)
		(fp_line
			(start -0.7874 -0.4064)
			(end 0.7874 -0.4064)
			(stroke
				(width 0.1524)
				(type default)
			)
			(layer "F.SilkS")
		)
		(fp_line
			(start 0.67945 0.3048)
			(end 0.120396 0.3048)
			(stroke
				(width 0.1)
				(type default)
			)
			(layer "F.Fab")
		)
		(fp_line
			(start 0.67945 -0.3048)
			(end 0.67945 0.3048)
			(stroke
				(width 0.1)
				(type default)
			)
			(layer "F.Fab")
		)
		(fp_line
			(start 0.12065 -0.2794)
			(end 0.12065 -0.3048)
			(stroke
				(width 0.1)
				(type default)
			)
			(layer "F.Fab")
		)
		(fp_line
			(start 0.12065 -0.3048)
			(end 0.67945 -0.3048)
			(stroke
				(width 0.1)
				(type default)
			)
			(layer "F.Fab")
		)
		(fp_line
			(start 0.120396 0.3048)
			(end 0.120396 0.2794)
			(stroke
				(width 0.1)
				(type default)
			)
			(layer "F.Fab")
		)
		(fp_line
			(start 0.120396 0.2794)
			(end -0.12065 0.2794)
			(stroke
				(width 0.1)
				(type default)
			)
			(layer "F.Fab")
		)
		(fp_line
			(start -0.12065 0.3048)
			(end -0.67945 0.3048)
			(stroke
				(width 0.1)
				(type default)
			)
			(layer "F.Fab")
		)
		(fp_line
			(start -0.12065 0.2794)
			(end -0.12065 0.3048)
			(stroke
				(width 0.1)
				(type default)
			)
			(layer "F.Fab")
		)
		(fp_line
			(start -0.12065 -0.2794)
			(end 0.12065 -0.2794)
			(stroke
				(width 0.1)
				(type default)
			)
			(layer "F.Fab")
		)
		(fp_line
			(start -0.12065 -0.305054)
			(end -0.12065 -0.2794)
			(stroke
				(width 0.1)
				(type default)
			)
			(layer "F.Fab")
		)
		(fp_line
			(start -0.67945 0.3048)
			(end -0.67945 -0.305054)
			(stroke
				(width 0.1)
				(type default)
			)
			(layer "F.Fab")
		)
		(fp_line
			(start -0.67945 -0.305054)
			(end -0.12065 -0.305054)
			(stroke
				(width 0.1)
				(type default)
			)
			(layer "F.Fab")
		)
		(pad "1" smd circle
			(at -0.40005 0 180)
			(size 0 0)
			(layers "F.Cu" "F.Mask" "F.Paste")
			(net "P3V3_AUX")
		)
		(pad "2" smd circle
			(at 0.40005 0 180)
			(size 0 0)
			(layers "F.Cu" "F.Mask" "F.Paste")
			(net "IRQ_HSC_FAULT")
		)
	)
	(footprint ""
		(layer "F.Cu")
		(at 166.18077 -395.6304 -90)
		(property "Reference" "R6794"
			(at 0 0 270)
			(layer "F.SilkS")
			(hide yes)
			(effects
				(font
					(size 1.27 1.27)
				)
			)
		)
		(property "Value" ""
			(at 0 0 270)
			(layer "F.Fab")
			(effects
				(font
					(size 1.27 1.27)
				)
			)
		)
		(duplicate_pad_numbers_are_jumpers no)
		(fp_line
			(start -0.32512 0.175006)
			(end -0.32512 -0.175006)
			(stroke
				(width 0.1)
				(type default)
			)
			(layer "F.Fab")
		)
		(fp_line
			(start 0.32512 0.175006)
			(end -0.32512 0.175006)
			(stroke
				(width 0.1)
				(type default)
			)
			(layer "F.Fab")
		)
		(fp_line
			(start -0.32512 -0.175006)
			(end 0.32512 -0.175006)
			(stroke
				(width 0.1)
				(type default)
			)
			(layer "F.Fab")
		)
		(fp_line
			(start 0.32512 -0.175006)
			(end 0.32512 0.175006)
			(stroke
				(width 0.1)
				(type default)
			)
			(layer "F.Fab")
		)
		(pad "1" smd rect
			(at -0.2667 0 270)
			(size 0.3048 0.381)
			(layers "F.Cu" "F.Mask" "F.Paste")
			(net "P1V8_CPU1_RT_1D")
		)
		(pad "2" smd rect
			(at 0.2667 0 90)
			(size 0.3048 0.381)
			(layers "F.Cu" "F.Mask" "F.Paste")
			(net "RT_CPU1_P2_VQPS")
		)
	)
	(footprint ""
		(layer "F.Cu")
		(at 441.530486 -21.676106)
		(property "Reference" "R1301"
			(at 0 0 0)
			(layer "F.SilkS")
			(hide yes)
			(effects
				(font
					(size 1.27 1.27)
				)
			)
		)
		(property "Value" ""
			(at 0 0 0)
			(layer "F.Fab")
			(effects
				(font
					(size 1.27 1.27)
				)
			)
		)
		(duplicate_pad_numbers_are_jumpers no)
		(fp_line
			(start -0.7874 -0.4064)
			(end 0.7874 -0.4064)
			(stroke
				(width 0.1524)
				(type default)
			)
			(layer "F.SilkS")
		)
		(fp_line
			(start -0.7874 0.4064)
			(end -0.7874 -0.4064)
			(stroke
				(width 0.1524)
				(type default)
			)
			(layer "F.SilkS")
		)
		(fp_line
			(start 0.7874 -0.4064)
			(end 0.7874 0.4064)
			(stroke
				(width 0.1524)
				(type default)
			)
			(layer "F.SilkS")
		)
		(fp_line
			(start 0.7874 0.4064)
			(end -0.7874 0.4064)
			(stroke
				(width 0.1524)
				(type default)
			)
			(layer "F.SilkS")
		)
		(fp_line
			(start -0.67945 -0.305054)
			(end -0.12065 -0.305054)
			(stroke
				(width 0.1)
				(type default)
			)
			(layer "F.Fab")
		)
		(fp_line
			(start -0.67945 0.3048)
			(end -0.67945 -0.305054)
			(stroke
				(width 0.1)
				(type default)
			)
			(layer "F.Fab")
		)
		(fp_line
			(start -0.12065 -0.305054)
			(end -0.12065 -0.2794)
			(stroke
				(width 0.1)
				(type default)
			)
			(layer "F.Fab")
		)
		(fp_line
			(start -0.12065 -0.2794)
			(end 0.12065 -0.2794)
			(stroke
				(width 0.1)
				(type default)
			)
			(layer "F.Fab")
		)
		(fp_line
			(start -0.12065 0.2794)
			(end -0.12065 0.3048)
			(stroke
				(width 0.1)
				(type default)
			)
			(layer "F.Fab")
		)
		(fp_line
			(start -0.12065 0.3048)
			(end -0.67945 0.3048)
			(stroke
				(width 0.1)
				(type default)
			)
			(layer "F.Fab")
		)
		(fp_line
			(start 0.120396 0.2794)
			(end -0.12065 0.2794)
			(stroke
				(width 0.1)
				(type default)
			)
			(layer "F.Fab")
		)
		(fp_line
			(start 0.120396 0.3048)
			(end 0.120396 0.2794)
			(stroke
				(width 0.1)
				(type default)
			)
			(layer "F.Fab")
		)
		(fp_line
			(start 0.12065 -0.3048)
			(end 0.67945 -0.3048)
			(stroke
				(width 0.1)
				(type default)
			)
			(layer "F.Fab")
		)
		(fp_line
			(start 0.12065 -0.2794)
			(end 0.12065 -0.3048)
			(stroke
				(width 0.1)
				(type default)
			)
			(layer "F.Fab")
		)
		(fp_line
			(start 0.67945 -0.3048)
			(end 0.67945 0.3048)
			(stroke
				(width 0.1)
				(type default)
			)
			(layer "F.Fab")
		)
		(fp_line
			(start 0.67945 0.3048)
			(end 0.120396 0.3048)
			(stroke
				(width 0.1)
				(type default)
			)
			(layer "F.Fab")
		)
		(pad "1" smd circle
			(at -0.40005 0)
			(size 0 0)
			(layers "F.Cu" "F.Mask" "F.Paste")
			(net "P12V_OCP_SFF_R")
		)
		(pad "2" smd circle
			(at 0.40005 0)
			(size 0 0)
			(layers "F.Cu" "F.Mask" "F.Paste")
			(net "VSENSE_P12V_INA230_6_INN")
		)
	)
	(footprint ""
		(layer "F.Cu")
		(at 412.472886 -76.896468 180)
		(property "Reference" "R47"
			(at 0 0 180)
			(layer "F.SilkS")
			(hide yes)
			(effects
				(font
					(size 1.27 1.27)
				)
			)
		)
		(property "Value" ""
			(at 0 0 180)
			(layer "F.Fab")
			(effects
				(font
					(size 1.27 1.27)
				)
			)
		)
		(duplicate_pad_numbers_are_jumpers no)
		(fp_line
			(start 0.7874 0.4064)
			(end -0.7874 0.4064)
			(stroke
				(width 0.1524)
				(type default)
			)
			(layer "F.SilkS")
		)
		(fp_line
			(start 0.7874 -0.4064)
			(end 0.7874 0.4064)
			(stroke
				(width 0.1524)
				(type default)
			)
			(layer "F.SilkS")
		)
		(fp_line
			(start -0.7874 0.4064)
			(end -0.7874 -0.4064)
			(stroke
				(width 0.1524)
				(type default)
			)
			(layer "F.SilkS")
		)
		(fp_line
			(start -0.7874 -0.4064)
			(end 0.7874 -0.4064)
			(stroke
				(width 0.1524)
				(type default)
			)
			(layer "F.SilkS")
		)
		(fp_line
			(start 0.67945 0.3048)
			(end 0.120396 0.3048)
			(stroke
				(width 0.1)
				(type default)
			)
			(layer "F.Fab")
		)
		(fp_line
			(start 0.67945 -0.3048)
			(end 0.67945 0.3048)
			(stroke
				(width 0.1)
				(type default)
			)
			(layer "F.Fab")
		)
		(fp_line
			(start 0.12065 -0.2794)
			(end 0.12065 -0.3048)
			(stroke
				(width 0.1)
				(type default)
			)
			(layer "F.Fab")
		)
		(fp_line
			(start 0.12065 -0.3048)
			(end 0.67945 -0.3048)
			(stroke
				(width 0.1)
				(type default)
			)
			(layer "F.Fab")
		)
		(fp_line
			(start 0.120396 0.3048)
			(end 0.120396 0.2794)
			(stroke
				(width 0.1)
				(type default)
			)
			(layer "F.Fab")
		)
		(fp_line
			(start 0.120396 0.2794)
			(end -0.12065 0.2794)
			(stroke
				(width 0.1)
				(type default)
			)
			(layer "F.Fab")
		)
		(fp_line
			(start -0.12065 0.3048)
			(end -0.67945 0.3048)
			(stroke
				(width 0.1)
				(type default)
			)
			(layer "F.Fab")
		)
		(fp_line
			(start -0.12065 0.2794)
			(end -0.12065 0.3048)
			(stroke
				(width 0.1)
				(type default)
			)
			(layer "F.Fab")
		)
		(fp_line
			(start -0.12065 -0.2794)
			(end 0.12065 -0.2794)
			(stroke
				(width 0.1)
				(type default)
			)
			(layer "F.Fab")
		)
		(fp_line
			(start -0.12065 -0.305054)
			(end -0.12065 -0.2794)
			(stroke
				(width 0.1)
				(type default)
			)
			(layer "F.Fab")
		)
		(fp_line
			(start -0.67945 0.3048)
			(end -0.67945 -0.305054)
			(stroke
				(width 0.1)
				(type default)
			)
			(layer "F.Fab")
		)
		(fp_line
			(start -0.67945 -0.305054)
			(end -0.12065 -0.305054)
			(stroke
				(width 0.1)
				(type default)
			)
			(layer "F.Fab")
		)
		(pad "1" smd circle
			(at -0.40005 0 180)
			(size 0 0)
			(layers "F.Cu" "F.Mask" "F.Paste")
			(net "SMB_OCP_SFF_3V3AUX_BUF_R_SCL")
		)
		(pad "2" smd circle
			(at 0.40005 0 180)
			(size 0 0)
			(layers "F.Cu" "F.Mask" "F.Paste")
			(net "SMB_OCP_SFF_3V3AUX_BUF_SCL")
		)
	)
	(footprint ""
		(layer "F.Cu")
		(at 100.48367 -407.167588 180)
		(property "Reference" "R594"
			(at 0 0 180)
			(layer "F.SilkS")
			(hide yes)
			(effects
				(font
					(size 1.27 1.27)
				)
			)
		)
		(property "Value" ""
			(at 0 0 180)
			(layer "F.Fab")
			(effects
				(font
					(size 1.27 1.27)
				)
			)
		)
		(duplicate_pad_numbers_are_jumpers no)
		(fp_line
			(start 0.7874 0.4064)
			(end -0.7874 0.4064)
			(stroke
				(width 0.1524)
				(type default)
			)
			(layer "F.SilkS")
		)
		(fp_line
			(start 0.7874 -0.4064)
			(end 0.7874 0.4064)
			(stroke
				(width 0.1524)
				(type default)
			)
			(layer "F.SilkS")
		)
		(fp_line
			(start -0.7874 0.4064)
			(end -0.7874 -0.4064)
			(stroke
				(width 0.1524)
				(type default)
			)
			(layer "F.SilkS")
		)
		(fp_line
			(start -0.7874 -0.4064)
			(end 0.7874 -0.4064)
			(stroke
				(width 0.1524)
				(type default)
			)
			(layer "F.SilkS")
		)
		(fp_line
			(start 0.67945 0.3048)
			(end 0.120396 0.3048)
			(stroke
				(width 0.1)
				(type default)
			)
			(layer "F.Fab")
		)
		(fp_line
			(start 0.67945 -0.3048)
			(end 0.67945 0.3048)
			(stroke
				(width 0.1)
				(type default)
			)
			(layer "F.Fab")
		)
		(fp_line
			(start 0.12065 -0.2794)
			(end 0.12065 -0.3048)
			(stroke
				(width 0.1)
				(type default)
			)
			(layer "F.Fab")
		)
		(fp_line
			(start 0.12065 -0.3048)
			(end 0.67945 -0.3048)
			(stroke
				(width 0.1)
				(type default)
			)
			(layer "F.Fab")
		)
		(fp_line
			(start 0.120396 0.3048)
			(end 0.120396 0.2794)
			(stroke
				(width 0.1)
				(type default)
			)
			(layer "F.Fab")
		)
		(fp_line
			(start 0.120396 0.2794)
			(end -0.12065 0.2794)
			(stroke
				(width 0.1)
				(type default)
			)
			(layer "F.Fab")
		)
		(fp_line
			(start -0.12065 0.3048)
			(end -0.67945 0.3048)
			(stroke
				(width 0.1)
				(type default)
			)
			(layer "F.Fab")
		)
		(fp_line
			(start -0.12065 0.2794)
			(end -0.12065 0.3048)
			(stroke
				(width 0.1)
				(type default)
			)
			(layer "F.Fab")
		)
		(fp_line
			(start -0.12065 -0.2794)
			(end 0.12065 -0.2794)
			(stroke
				(width 0.1)
				(type default)
			)
			(layer "F.Fab")
		)
		(fp_line
			(start -0.12065 -0.305054)
			(end -0.12065 -0.2794)
			(stroke
				(width 0.1)
				(type default)
			)
			(layer "F.Fab")
		)
		(fp_line
			(start -0.67945 0.3048)
			(end -0.67945 -0.305054)
			(stroke
				(width 0.1)
				(type default)
			)
			(layer "F.Fab")
		)
		(fp_line
			(start -0.67945 -0.305054)
			(end -0.12065 -0.305054)
			(stroke
				(width 0.1)
				(type default)
			)
			(layer "F.Fab")
		)
		(pad "1" smd circle
			(at -0.40005 0 180)
			(size 0 0)
			(layers "F.Cu" "F.Mask" "F.Paste")
			(net "FM_9ZXL045_P1_0_OE_N")
		)
		(pad "2" smd circle
			(at 0.40005 0 180)
			(size 0 0)
			(layers "F.Cu" "F.Mask" "F.Paste")
			(net "GND")
		)
	)
	(footprint ""
		(layer "F.Cu")
		(at 146.776186 -54.913784 -90)
		(property "Reference" "C1503"
			(at 0 0 270)
			(layer "F.SilkS")
			(hide yes)
			(effects
				(font
					(size 1.27 1.27)
				)
			)
		)
		(property "Value" ""
			(at 0 0 270)
			(layer "F.Fab")
			(effects
				(font
					(size 1.27 1.27)
				)
			)
		)
		(duplicate_pad_numbers_are_jumpers no)
		(fp_line
			(start -0.7874 0.4064)
			(end -0.7874 -0.4064)
			(stroke
				(width 0.1524)
				(type default)
			)
			(layer "F.SilkS")
		)
		(fp_line
			(start 0.7874 0.4064)
			(end -0.7874 0.4064)
			(stroke
				(width 0.1524)
				(type default)
			)
			(layer "F.SilkS")
		)
		(fp_line
			(start -0.7874 -0.4064)
			(end 0.7874 -0.4064)
			(stroke
				(width 0.1524)
				(type default)
			)
			(layer "F.SilkS")
		)
		(fp_line
			(start 0.7874 -0.4064)
			(end 0.7874 0.4064)
			(stroke
				(width 0.1524)
				(type default)
			)
			(layer "F.SilkS")
		)
		(fp_line
			(start -0.67945 0.3048)
			(end -0.67945 -0.305054)
			(stroke
				(width 0.1)
				(type default)
			)
			(layer "F.Fab")
		)
		(fp_line
			(start -0.12065 0.3048)
			(end -0.67945 0.3048)
			(stroke
				(width 0.1)
				(type default)
			)
			(layer "F.Fab")
		)
		(fp_line
			(start 0.120396 0.3048)
			(end 0.120396 0.2794)
			(stroke
				(width 0.1)
				(type default)
			)
			(layer "F.Fab")
		)
		(fp_line
			(start 0.67945 0.3048)
			(end 0.120396 0.3048)
			(stroke
				(width 0.1)
				(type default)
			)
			(layer "F.Fab")
		)
		(fp_line
			(start -0.12065 0.2794)
			(end -0.12065 0.3048)
			(stroke
				(width 0.1)
				(type default)
			)
			(layer "F.Fab")
		)
		(fp_line
			(start 0.120396 0.2794)
			(end -0.12065 0.2794)
			(stroke
				(width 0.1)
				(type default)
			)
			(layer "F.Fab")
		)
		(fp_line
			(start -0.12065 -0.2794)
			(end 0.12065 -0.2794)
			(stroke
				(width 0.1)
				(type default)
			)
			(layer "F.Fab")
		)
		(fp_line
			(start 0.12065 -0.2794)
			(end 0.12065 -0.3048)
			(stroke
				(width 0.1)
				(type default)
			)
			(layer "F.Fab")
		)
		(fp_line
			(start 0.12065 -0.3048)
			(end 0.67945 -0.3048)
			(stroke
				(width 0.1)
				(type default)
			)
			(layer "F.Fab")
		)
		(fp_line
			(start 0.67945 -0.3048)
			(end 0.67945 0.3048)
			(stroke
				(width 0.1)
				(type default)
			)
			(layer "F.Fab")
		)
		(fp_line
			(start -0.67945 -0.305054)
			(end -0.12065 -0.305054)
			(stroke
				(width 0.1)
				(type default)
			)
			(layer "F.Fab")
		)
		(fp_line
			(start -0.12065 -0.305054)
			(end -0.12065 -0.2794)
			(stroke
				(width 0.1)
				(type default)
			)
			(layer "F.Fab")
		)
		(pad "1" smd circle
			(at -0.40005 0 270)
			(size 0 0)
			(layers "F.Cu" "F.Mask" "F.Paste")
			(net "P3V3_AUX")
		)
		(pad "2" smd circle
			(at 0.40005 0 270)
			(size 0 0)
			(layers "F.Cu" "F.Mask" "F.Paste")
			(net "GND")
		)
	)
	(footprint ""
		(layer "F.Cu")
		(at 446.634616 -390.076944 -90)
		(property "Reference" "PL6505"
			(at 1.075944 -11.862054 90)
			(unlocked yes)
			(layer "F.SilkS")
			(effects
				(font
					(size 0.7874 0.5842)
					(thickness 0.1524)
				)
				(justify left)
			)
		)
		(property "Value" ""
			(at 0 0 270)
			(layer "F.Fab")
			(effects
				(font
					(size 1.27 1.27)
				)
			)
		)
		(duplicate_pad_numbers_are_jumpers no)
		(fp_line
			(start -3.24993 3.24993)
			(end -3.24993 2.2352)
			(stroke
				(width 0.1524)
				(type default)
			)
			(layer "F.SilkS")
		)
		(fp_line
			(start 3.24993 3.24993)
			(end -3.24993 3.24993)
			(stroke
				(width 0.1524)
				(type default)
			)
			(layer "F.SilkS")
		)
		(fp_line
			(start 3.24993 2.2352)
			(end 3.24993 3.24993)
			(stroke
				(width 0.1524)
				(type default)
			)
			(layer "F.SilkS")
		)
		(fp_line
			(start -3.24993 -2.2352)
			(end -3.24993 -3.24993)
			(stroke
				(width 0.1524)
				(type default)
			)
			(layer "F.SilkS")
		)
		(fp_line
			(start -3.24993 -3.24993)
			(end 3.24993 -3.24993)
			(stroke
				(width 0.1524)
				(type default)
			)
			(layer "F.SilkS")
		)
		(fp_line
			(start 3.24993 -3.24993)
			(end 3.24993 -2.2352)
			(stroke
				(width 0.1524)
				(type default)
			)
			(layer "F.SilkS")
		)
		(fp_line
			(start -3.24993 3.24993)
			(end -3.24993 -3.24993)
			(stroke
				(width 0.1)
				(type default)
			)
			(layer "F.Fab")
		)
		(fp_line
			(start 3.24993 3.24993)
			(end -3.24993 3.24993)
			(stroke
				(width 0.1)
				(type default)
			)
			(layer "F.Fab")
		)
		(fp_line
			(start -3.24993 -3.24993)
			(end 3.24993 -3.24993)
			(stroke
				(width 0.1)
				(type default)
			)
			(layer "F.Fab")
		)
		(fp_line
			(start 3.24993 -3.24993)
			(end 3.24993 3.24993)
			(stroke
				(width 0.1)
				(type default)
			)
			(layer "F.Fab")
		)
		(pad "1" smd rect
			(at -2.29997 0 270)
			(size 2.0066 4.2164)
			(layers "F.Cu" "F.Mask" "F.Paste")
			(net "SW_P0V9_RETIMER_CPU0_SW1")
		)
		(pad "2" smd rect
			(at 2.29997 0 270)
			(size 2.0066 4.2164)
			(layers "F.Cu" "F.Mask" "F.Paste")
			(net "P0V9_CPU0_RT_2D")
		)
	)
)
